(kicad_pcb
	(version 20260206)
	(generator "pcbnew")
	(generator_version "10.0")
	(general
		(thickness 1.6)
		(legacy_teardrops no)
	)
	(paper "A4")
	(title_block
		(title "04192023_DAF0TMB3IC0_F0TG_MB_C_brd_V02_OCP.brd")
		(comment 1 "Grand Teton / footprints 6566-6572 of 8354")
	)
	(layers
		(0 "F.Cu" signal "TOP")
		(4 "In1.Cu" signal "GND")
		(6 "In2.Cu" signal "IN1")
		(8 "In3.Cu" signal "GND1")
		(10 "In4.Cu" signal "IN2")
		(12 "In5.Cu" signal "GND2")
		(14 "In6.Cu" signal "IN3")
		(16 "In7.Cu" signal "GND3")
		(18 "In8.Cu" signal "VCC")
		(20 "In9.Cu" signal "VCC1")
		(22 "In10.Cu" signal "GND4")
		(24 "In11.Cu" signal "IN4")
		(26 "In12.Cu" signal "GND5")
		(28 "In13.Cu" signal "IN5")
		(30 "In14.Cu" signal "GND6")
		(32 "In15.Cu" signal "IN6")
		(34 "In16.Cu" signal "GND7")
		(2 "B.Cu" signal "BOTTOM")
		(9 "F.Adhes" user "F.Adhesive")
		(11 "B.Adhes" user "B.Adhesive")
		(13 "F.Paste" user "Package Geometry/Pastemask Top")
		(15 "B.Paste" user "Package Geometry/Pastemask Bottom")
		(5 "F.SilkS" user "Ref Des/Silkscreen Top")
		(7 "B.SilkS" user "Ref Des/Silkscreen Bottom")
		(1 "F.Mask" user "Board Geometry/Soldermask Top")
		(3 "B.Mask" user "Board Geometry/Soldermask Bottom")
		(17 "Dwgs.User" user "User.Drawings")
		(19 "Cmts.User" user "User.Comments")
		(21 "Eco1.User" user "User.Eco1")
		(23 "Eco2.User" user "User.Eco2")
		(25 "Edge.Cuts" user "Board Geometry/Outline")
		(27 "Margin" user)
		(31 "F.CrtYd" user "Package Geometry/Place Bound Top")
		(29 "B.CrtYd" user "Package Geometry/Place Bound Bottom")
		(35 "F.Fab" user "Ref Des/Assembly Top")
		(33 "B.Fab" user "Ref Des/Assembly Bottom")
	)
	(footprint ""
		(layer "B.Cu")
		(at 67.201034 -196.95414)
		(property "Reference" "R6503"
			(at 0 0 0)
			(layer "B.SilkS")
			(hide yes)
			(effects
				(font
					(size 1.27 1.27)
				)
				(justify mirror)
			)
		)
		(property "Value" ""
			(at 0 0 0)
			(layer "B.Fab")
			(effects
				(font
					(size 1.27 1.27)
				)
				(justify mirror)
			)
		)
		(duplicate_pad_numbers_are_jumpers no)
		(fp_line
			(start -0.7874 -0.4064)
			(end -0.7874 0.4064)
			(stroke
				(width 0.1524)
				(type default)
			)
			(layer "B.SilkS")
		)
		(fp_line
			(start -0.7874 0.4064)
			(end 0.7874 0.4064)
			(stroke
				(width 0.1524)
				(type default)
			)
			(layer "B.SilkS")
		)
		(fp_line
			(start 0.7874 -0.4064)
			(end -0.7874 -0.4064)
			(stroke
				(width 0.1524)
				(type default)
			)
			(layer "B.SilkS")
		)
		(fp_line
			(start 0.7874 0.4064)
			(end 0.7874 -0.4064)
			(stroke
				(width 0.1524)
				(type default)
			)
			(layer "B.SilkS")
		)
		(fp_line
			(start -0.67945 -0.3048)
			(end -0.67945 0.3048)
			(stroke
				(width 0.1)
				(type default)
			)
			(layer "B.Fab")
		)
		(fp_line
			(start -0.67945 0.3048)
			(end -0.120396 0.3048)
			(stroke
				(width 0.1)
				(type default)
			)
			(layer "B.Fab")
		)
		(fp_line
			(start -0.12065 -0.3048)
			(end -0.67945 -0.3048)
			(stroke
				(width 0.1)
				(type default)
			)
			(layer "B.Fab")
		)
		(fp_line
			(start -0.12065 -0.2794)
			(end -0.12065 -0.3048)
			(stroke
				(width 0.1)
				(type default)
			)
			(layer "B.Fab")
		)
		(fp_line
			(start -0.120396 0.2794)
			(end 0.12065 0.2794)
			(stroke
				(width 0.1)
				(type default)
			)
			(layer "B.Fab")
		)
		(fp_line
			(start -0.120396 0.3048)
			(end -0.120396 0.2794)
			(stroke
				(width 0.1)
				(type default)
			)
			(layer "B.Fab")
		)
		(fp_line
			(start 0.12065 -0.305054)
			(end 0.12065 -0.2794)
			(stroke
				(width 0.1)
				(type default)
			)
			(layer "B.Fab")
		)
		(fp_line
			(start 0.12065 -0.2794)
			(end -0.12065 -0.2794)
			(stroke
				(width 0.1)
				(type default)
			)
			(layer "B.Fab")
		)
		(fp_line
			(start 0.12065 0.2794)
			(end 0.12065 0.3048)
			(stroke
				(width 0.1)
				(type default)
			)
			(layer "B.Fab")
		)
		(fp_line
			(start 0.12065 0.3048)
			(end 0.67945 0.3048)
			(stroke
				(width 0.1)
				(type default)
			)
			(layer "B.Fab")
		)
		(fp_line
			(start 0.67945 -0.305054)
			(end 0.12065 -0.305054)
			(stroke
				(width 0.1)
				(type default)
			)
			(layer "B.Fab")
		)
		(fp_line
			(start 0.67945 0.3048)
			(end 0.67945 -0.305054)
			(stroke
				(width 0.1)
				(type default)
			)
			(layer "B.Fab")
		)
		(pad "1" smd circle
			(at 0.40005 0 180)
			(size 0 0)
			(layers "B.Cu" "B.Mask" "B.Paste")
			(net "CPU1_FORCE_SELFREFRESH")
		)
		(pad "2" smd circle
			(at -0.40005 0 180)
			(size 0 0)
			(layers "B.Cu" "B.Mask" "B.Paste")
			(net "GND")
		)
	)
	(footprint ""
		(layer "B.Cu")
		(at 432.997102 -351.058226 90)
		(property "Reference" "PC214_2"
			(at 0 0 90)
			(layer "B.SilkS")
			(hide yes)
			(effects
				(font
					(size 1.27 1.27)
				)
				(justify mirror)
			)
		)
		(property "Value" ""
			(at 0 0 90)
			(layer "B.Fab")
			(effects
				(font
					(size 1.27 1.27)
				)
				(justify mirror)
			)
		)
		(duplicate_pad_numbers_are_jumpers no)
		(fp_line
			(start 1.524 -0.762)
			(end -1.524 -0.762)
			(stroke
				(width 0.1524)
				(type default)
			)
			(layer "B.SilkS")
		)
		(fp_line
			(start -1.524 -0.762)
			(end -1.524 0.762)
			(stroke
				(width 0.1524)
				(type default)
			)
			(layer "B.SilkS")
		)
		(fp_line
			(start 1.524 0.762)
			(end 1.524 -0.762)
			(stroke
				(width 0.1524)
				(type default)
			)
			(layer "B.SilkS")
		)
		(fp_line
			(start -1.524 0.762)
			(end 1.524 0.762)
			(stroke
				(width 0.1524)
				(type default)
			)
			(layer "B.SilkS")
		)
		(fp_line
			(start 1.1049 -0.724916)
			(end 1.1049 0.724916)
			(stroke
				(width 0.1)
				(type default)
			)
			(layer "B.Fab")
		)
		(fp_line
			(start -1.1049 -0.724916)
			(end 1.1049 -0.724916)
			(stroke
				(width 0.1)
				(type default)
			)
			(layer "B.Fab")
		)
		(fp_line
			(start 1.1049 0.724916)
			(end -1.1049 0.724916)
			(stroke
				(width 0.1)
				(type default)
			)
			(layer "B.Fab")
		)
		(fp_line
			(start -1.1049 0.724916)
			(end -1.1049 -0.724916)
			(stroke
				(width 0.1)
				(type default)
			)
			(layer "B.Fab")
		)
		(pad "1" smd rect
			(at 0.889 0 90)
			(size 1.016 1.27)
			(layers "B.Cu" "B.Mask" "B.Paste")
			(net "SW_P12V_AUX_PVDD11_S3_P0_FLT")
		)
		(pad "2" smd rect
			(at -0.889 0 90)
			(size 1.016 1.27)
			(layers "B.Cu" "B.Mask" "B.Paste")
			(net "GND")
		)
	)
	(footprint ""
		(layer "B.Cu")
		(at 117.83314 -267.529564)
		(property "Reference" "C2392"
			(at 0 0 0)
			(layer "B.SilkS")
			(hide yes)
			(effects
				(font
					(size 1.27 1.27)
				)
				(justify mirror)
			)
		)
		(property "Value" ""
			(at 0 0 0)
			(layer "B.Fab")
			(effects
				(font
					(size 1.27 1.27)
				)
				(justify mirror)
			)
		)
		(duplicate_pad_numbers_are_jumpers no)
		(fp_line
			(start -0.7874 -0.4064)
			(end -0.7874 0.4064)
			(stroke
				(width 0.1524)
				(type default)
			)
			(layer "B.SilkS")
		)
		(fp_line
			(start -0.7874 0.4064)
			(end 0.7874 0.4064)
			(stroke
				(width 0.1524)
				(type default)
			)
			(layer "B.SilkS")
		)
		(fp_line
			(start 0.7874 -0.4064)
			(end -0.7874 -0.4064)
			(stroke
				(width 0.1524)
				(type default)
			)
			(layer "B.SilkS")
		)
		(fp_line
			(start 0.7874 0.4064)
			(end 0.7874 -0.4064)
			(stroke
				(width 0.1524)
				(type default)
			)
			(layer "B.SilkS")
		)
		(fp_line
			(start -0.67945 -0.3048)
			(end -0.67945 0.3048)
			(stroke
				(width 0.1)
				(type default)
			)
			(layer "B.Fab")
		)
		(fp_line
			(start -0.67945 0.3048)
			(end -0.120396 0.3048)
			(stroke
				(width 0.1)
				(type default)
			)
			(layer "B.Fab")
		)
		(fp_line
			(start -0.12065 -0.3048)
			(end -0.67945 -0.3048)
			(stroke
				(width 0.1)
				(type default)
			)
			(layer "B.Fab")
		)
		(fp_line
			(start -0.12065 -0.2794)
			(end -0.12065 -0.3048)
			(stroke
				(width 0.1)
				(type default)
			)
			(layer "B.Fab")
		)
		(fp_line
			(start -0.120396 0.2794)
			(end 0.12065 0.2794)
			(stroke
				(width 0.1)
				(type default)
			)
			(layer "B.Fab")
		)
		(fp_line
			(start -0.120396 0.3048)
			(end -0.120396 0.2794)
			(stroke
				(width 0.1)
				(type default)
			)
			(layer "B.Fab")
		)
		(fp_line
			(start 0.12065 -0.305054)
			(end 0.12065 -0.2794)
			(stroke
				(width 0.1)
				(type default)
			)
			(layer "B.Fab")
		)
		(fp_line
			(start 0.12065 -0.2794)
			(end -0.12065 -0.2794)
			(stroke
				(width 0.1)
				(type default)
			)
			(layer "B.Fab")
		)
		(fp_line
			(start 0.12065 0.2794)
			(end 0.12065 0.3048)
			(stroke
				(width 0.1)
				(type default)
			)
			(layer "B.Fab")
		)
		(fp_line
			(start 0.12065 0.3048)
			(end 0.67945 0.3048)
			(stroke
				(width 0.1)
				(type default)
			)
			(layer "B.Fab")
		)
		(fp_line
			(start 0.67945 -0.305054)
			(end 0.12065 -0.305054)
			(stroke
				(width 0.1)
				(type default)
			)
			(layer "B.Fab")
		)
		(fp_line
			(start 0.67945 0.3048)
			(end 0.67945 -0.305054)
			(stroke
				(width 0.1)
				(type default)
			)
			(layer "B.Fab")
		)
		(pad "1" smd circle
			(at 0.40005 0 180)
			(size 0 0)
			(layers "B.Cu" "B.Mask" "B.Paste")
			(net "PVDDCR_CPU1_P1")
		)
		(pad "2" smd circle
			(at -0.40005 0 180)
			(size 0 0)
			(layers "B.Cu" "B.Mask" "B.Paste")
			(net "GND")
		)
	)
	(footprint ""
		(layer "B.Cu")
		(at 178.981608 -126.833376 90)
		(property "Reference" "R6711"
			(at 0 0 90)
			(layer "B.SilkS")
			(hide yes)
			(effects
				(font
					(size 1.27 1.27)
				)
				(justify mirror)
			)
		)
		(property "Value" ""
			(at 0 0 90)
			(layer "B.Fab")
			(effects
				(font
					(size 1.27 1.27)
				)
				(justify mirror)
			)
		)
		(duplicate_pad_numbers_are_jumpers no)
		(fp_line
			(start 0.7874 -0.4064)
			(end -0.7874 -0.4064)
			(stroke
				(width 0.1524)
				(type default)
			)
			(layer "B.SilkS")
		)
		(fp_line
			(start -0.7874 -0.4064)
			(end -0.7874 0.4064)
			(stroke
				(width 0.1524)
				(type default)
			)
			(layer "B.SilkS")
		)
		(fp_line
			(start 0.7874 0.4064)
			(end 0.7874 -0.4064)
			(stroke
				(width 0.1524)
				(type default)
			)
			(layer "B.SilkS")
		)
		(fp_line
			(start -0.7874 0.4064)
			(end 0.7874 0.4064)
			(stroke
				(width 0.1524)
				(type default)
			)
			(layer "B.SilkS")
		)
		(fp_line
			(start 0.67945 -0.305054)
			(end 0.12065 -0.305054)
			(stroke
				(width 0.1)
				(type default)
			)
			(layer "B.Fab")
		)
		(fp_line
			(start 0.12065 -0.305054)
			(end 0.12065 -0.2794)
			(stroke
				(width 0.1)
				(type default)
			)
			(layer "B.Fab")
		)
		(fp_line
			(start -0.12065 -0.3048)
			(end -0.67945 -0.3048)
			(stroke
				(width 0.1)
				(type default)
			)
			(layer "B.Fab")
		)
		(fp_line
			(start -0.67945 -0.3048)
			(end -0.67945 0.3048)
			(stroke
				(width 0.1)
				(type default)
			)
			(layer "B.Fab")
		)
		(fp_line
			(start 0.12065 -0.2794)
			(end -0.12065 -0.2794)
			(stroke
				(width 0.1)
				(type default)
			)
			(layer "B.Fab")
		)
		(fp_line
			(start -0.12065 -0.2794)
			(end -0.12065 -0.3048)
			(stroke
				(width 0.1)
				(type default)
			)
			(layer "B.Fab")
		)
		(fp_line
			(start 0.12065 0.2794)
			(end 0.12065 0.3048)
			(stroke
				(width 0.1)
				(type default)
			)
			(layer "B.Fab")
		)
		(fp_line
			(start -0.120396 0.2794)
			(end 0.12065 0.2794)
			(stroke
				(width 0.1)
				(type default)
			)
			(layer "B.Fab")
		)
		(fp_line
			(start 0.67945 0.3048)
			(end 0.67945 -0.305054)
			(stroke
				(width 0.1)
				(type default)
			)
			(layer "B.Fab")
		)
		(fp_line
			(start 0.12065 0.3048)
			(end 0.67945 0.3048)
			(stroke
				(width 0.1)
				(type default)
			)
			(layer "B.Fab")
		)
		(fp_line
			(start -0.120396 0.3048)
			(end -0.120396 0.2794)
			(stroke
				(width 0.1)
				(type default)
			)
			(layer "B.Fab")
		)
		(fp_line
			(start -0.67945 0.3048)
			(end -0.120396 0.3048)
			(stroke
				(width 0.1)
				(type default)
			)
			(layer "B.Fab")
		)
		(pad "1" smd circle
			(at 0.40005 0 270)
			(size 0 0)
			(layers "B.Cu" "B.Mask" "B.Paste")
			(net "RST_RT_CPU1_P0_RESET_R_N")
		)
		(pad "2" smd circle
			(at -0.40005 0 270)
			(size 0 0)
			(layers "B.Cu" "B.Mask" "B.Paste")
			(net "RST_RT_CPU1_P0_RESET_R2_N")
		)
	)
	(footprint ""
		(layer "B.Cu")
		(at 100.271834 -265.045952)
		(property "Reference" "C2117"
			(at 0 0 0)
			(layer "B.SilkS")
			(hide yes)
			(effects
				(font
					(size 1.27 1.27)
				)
				(justify mirror)
			)
		)
		(property "Value" ""
			(at 0 0 0)
			(layer "B.Fab")
			(effects
				(font
					(size 1.27 1.27)
				)
				(justify mirror)
			)
		)
		(duplicate_pad_numbers_are_jumpers no)
		(fp_line
			(start -0.7874 -0.4064)
			(end -0.7874 0.4064)
			(stroke
				(width 0.1524)
				(type default)
			)
			(layer "B.SilkS")
		)
		(fp_line
			(start -0.7874 0.4064)
			(end 0.7874 0.4064)
			(stroke
				(width 0.1524)
				(type default)
			)
			(layer "B.SilkS")
		)
		(fp_line
			(start 0.7874 -0.4064)
			(end -0.7874 -0.4064)
			(stroke
				(width 0.1524)
				(type default)
			)
			(layer "B.SilkS")
		)
		(fp_line
			(start 0.7874 0.4064)
			(end 0.7874 -0.4064)
			(stroke
				(width 0.1524)
				(type default)
			)
			(layer "B.SilkS")
		)
		(fp_line
			(start -0.67945 -0.3048)
			(end -0.67945 0.3048)
			(stroke
				(width 0.1)
				(type default)
			)
			(layer "B.Fab")
		)
		(fp_line
			(start -0.67945 0.3048)
			(end -0.120396 0.3048)
			(stroke
				(width 0.1)
				(type default)
			)
			(layer "B.Fab")
		)
		(fp_line
			(start -0.12065 -0.3048)
			(end -0.67945 -0.3048)
			(stroke
				(width 0.1)
				(type default)
			)
			(layer "B.Fab")
		)
		(fp_line
			(start -0.12065 -0.2794)
			(end -0.12065 -0.3048)
			(stroke
				(width 0.1)
				(type default)
			)
			(layer "B.Fab")
		)
		(fp_line
			(start -0.120396 0.2794)
			(end 0.12065 0.2794)
			(stroke
				(width 0.1)
				(type default)
			)
			(layer "B.Fab")
		)
		(fp_line
			(start -0.120396 0.3048)
			(end -0.120396 0.2794)
			(stroke
				(width 0.1)
				(type default)
			)
			(layer "B.Fab")
		)
		(fp_line
			(start 0.12065 -0.305054)
			(end 0.12065 -0.2794)
			(stroke
				(width 0.1)
				(type default)
			)
			(layer "B.Fab")
		)
		(fp_line
			(start 0.12065 -0.2794)
			(end -0.12065 -0.2794)
			(stroke
				(width 0.1)
				(type default)
			)
			(layer "B.Fab")
		)
		(fp_line
			(start 0.12065 0.2794)
			(end 0.12065 0.3048)
			(stroke
				(width 0.1)
				(type default)
			)
			(layer "B.Fab")
		)
		(fp_line
			(start 0.12065 0.3048)
			(end 0.67945 0.3048)
			(stroke
				(width 0.1)
				(type default)
			)
			(layer "B.Fab")
		)
		(fp_line
			(start 0.67945 -0.305054)
			(end 0.12065 -0.305054)
			(stroke
				(width 0.1)
				(type default)
			)
			(layer "B.Fab")
		)
		(fp_line
			(start 0.67945 0.3048)
			(end 0.67945 -0.305054)
			(stroke
				(width 0.1)
				(type default)
			)
			(layer "B.Fab")
		)
		(pad "1" smd circle
			(at 0.40005 0 180)
			(size 0 0)
			(layers "B.Cu" "B.Mask" "B.Paste")
			(net "PVDDIO_P1")
		)
		(pad "2" smd circle
			(at -0.40005 0 180)
			(size 0 0)
			(layers "B.Cu" "B.Mask" "B.Paste")
			(net "GND")
		)
	)
	(footprint ""
		(layer "B.Cu")
		(at 141.53388 -33.475422)
		(property "Reference" "L6000"
			(at 0 0 0)
			(layer "B.SilkS")
			(hide yes)
			(effects
				(font
					(size 1.27 1.27)
				)
				(justify mirror)
			)
		)
		(property "Value" ""
			(at 0 0 0)
			(layer "B.Fab")
			(effects
				(font
					(size 1.27 1.27)
				)
				(justify mirror)
			)
		)
		(duplicate_pad_numbers_are_jumpers no)
		(fp_line
			(start -1.63576 -0.8128)
			(end -1.63576 0.8128)
			(stroke
				(width 0.1524)
				(type default)
			)
			(layer "B.SilkS")
		)
		(fp_line
			(start -1.63576 0.8128)
			(end 1.63576 0.8128)
			(stroke
				(width 0.1524)
				(type default)
			)
			(layer "B.SilkS")
		)
		(fp_line
			(start 1.63576 -0.8128)
			(end -1.63576 -0.8128)
			(stroke
				(width 0.1524)
				(type default)
			)
			(layer "B.SilkS")
		)
		(fp_line
			(start 1.63576 -0.8128)
			(end 1.63576 0.8128)
			(stroke
				(width 0.1524)
				(type default)
			)
			(layer "B.SilkS")
		)
		(fp_line
			(start -1.560576 -0.738632)
			(end 1.56083 -0.738632)
			(stroke
				(width 0.1)
				(type default)
			)
			(layer "B.Fab")
		)
		(fp_line
			(start -1.560576 0.7366)
			(end -1.560576 -0.738632)
			(stroke
				(width 0.1)
				(type default)
			)
			(layer "B.Fab")
		)
		(fp_line
			(start -1.524 0.7366)
			(end -1.560576 0.7366)
			(stroke
				(width 0.1)
				(type default)
			)
			(layer "B.Fab")
		)
		(fp_line
			(start 1.524 0.7366)
			(end -1.524 0.7366)
			(stroke
				(width 0.1)
				(type default)
			)
			(layer "B.Fab")
		)
		(fp_line
			(start 1.56083 -0.738632)
			(end 1.56083 0.7366)
			(stroke
				(width 0.1)
				(type default)
			)
			(layer "B.Fab")
		)
		(fp_line
			(start 1.56083 0.7366)
			(end 1.524 0.7366)
			(stroke
				(width 0.1)
				(type default)
			)
			(layer "B.Fab")
		)
		(pad "1" smd rect
			(at 0.94996 0)
			(size 1.1176 1.3716)
			(layers "B.Cu" "B.Mask" "B.Paste")
			(net "P3V3_AUX")
		)
		(pad "2" smd rect
			(at -0.94996 0)
			(size 1.1176 1.3716)
			(layers "B.Cu" "B.Mask" "B.Paste")
			(net "P3V3_AUX_CPU0_USB_AVDD33")
		)
	)
	(footprint ""
		(layer "B.Cu")
		(at 423.256456 -193.99631)
		(property "Reference" "C120"
			(at 0 0 0)
			(layer "B.SilkS")
			(hide yes)
			(effects
				(font
					(size 1.27 1.27)
				)
				(justify mirror)
			)
		)
		(property "Value" ""
			(at 0 0 0)
			(layer "B.Fab")
			(effects
				(font
					(size 1.27 1.27)
				)
				(justify mirror)
			)
		)
		(duplicate_pad_numbers_are_jumpers no)
		(fp_line
			(start -0.7874 -0.4064)
			(end -0.7874 0.4064)
			(stroke
				(width 0.1524)
				(type default)
			)
			(layer "B.SilkS")
		)
		(fp_line
			(start -0.7874 0.4064)
			(end 0.7874 0.4064)
			(stroke
				(width 0.1524)
				(type default)
			)
			(layer "B.SilkS")
		)
		(fp_line
			(start 0.7874 -0.4064)
			(end -0.7874 -0.4064)
			(stroke
				(width 0.1524)
				(type default)
			)
			(layer "B.SilkS")
		)
		(fp_line
			(start 0.7874 0.4064)
			(end 0.7874 -0.4064)
			(stroke
				(width 0.1524)
				(type default)
			)
			(layer "B.SilkS")
		)
		(fp_line
			(start -0.67945 -0.3048)
			(end -0.67945 0.3048)
			(stroke
				(width 0.1)
				(type default)
			)
			(layer "B.Fab")
		)
		(fp_line
			(start -0.67945 0.3048)
			(end -0.120396 0.3048)
			(stroke
				(width 0.1)
				(type default)
			)
			(layer "B.Fab")
		)
		(fp_line
			(start -0.12065 -0.3048)
			(end -0.67945 -0.3048)
			(stroke
				(width 0.1)
				(type default)
			)
			(layer "B.Fab")
		)
		(fp_line
			(start -0.12065 -0.2794)
			(end -0.12065 -0.3048)
			(stroke
				(width 0.1)
				(type default)
			)
			(layer "B.Fab")
		)
		(fp_line
			(start -0.120396 0.2794)
			(end 0.12065 0.2794)
			(stroke
				(width 0.1)
				(type default)
			)
			(layer "B.Fab")
		)
		(fp_line
			(start -0.120396 0.3048)
			(end -0.120396 0.2794)
			(stroke
				(width 0.1)
				(type default)
			)
			(layer "B.Fab")
		)
		(fp_line
			(start 0.12065 -0.305054)
			(end 0.12065 -0.2794)
			(stroke
				(width 0.1)
				(type default)
			)
			(layer "B.Fab")
		)
		(fp_line
			(start 0.12065 -0.2794)
			(end -0.12065 -0.2794)
			(stroke
				(width 0.1)
				(type default)
			)
			(layer "B.Fab")
		)
		(fp_line
			(start 0.12065 0.2794)
			(end 0.12065 0.3048)
			(stroke
				(width 0.1)
				(type default)
			)
			(layer "B.Fab")
		)
		(fp_line
			(start 0.12065 0.3048)
			(end 0.67945 0.3048)
			(stroke
				(width 0.1)
				(type default)
			)
			(layer "B.Fab")
		)
		(fp_line
			(start 0.67945 -0.305054)
			(end 0.12065 -0.305054)
			(stroke
				(width 0.1)
				(type default)
			)
			(layer "B.Fab")
		)
		(fp_line
			(start 0.67945 0.3048)
			(end 0.67945 -0.305054)
			(stroke
				(width 0.1)
				(type default)
			)
			(layer "B.Fab")
		)
		(pad "1" smd circle
			(at 0.40005 0 180)
			(size 0 0)
			(layers "B.Cu" "B.Mask" "B.Paste")
			(net "P3V3_AUX")
		)
		(pad "2" smd circle
			(at -0.40005 0 180)
			(size 0 0)
			(layers "B.Cu" "B.Mask" "B.Paste")
			(net "GND")
		)
	)
)
